(kicad_pcb
	(version 20260206)
	(generator "pcbnew")
	(generator_version "10.0")
	(general
		(thickness 1.6)
		(legacy_teardrops no)
	)
	(paper "A4")
	(title_block
		(title "03242023_DA0F0TMBIJ0_F0T_Motherboard_J_brd_V01_OCP.brd")
		(comment 1 "Grand Teton / footprints 5659-5665 of 6105")
	)
	(layers
		(0 "F.Cu" signal "TOP")
		(4 "In1.Cu" signal "GND")
		(6 "In2.Cu" signal "IN1")
		(8 "In3.Cu" signal "GND1")
		(10 "In4.Cu" signal "IN2")
		(12 "In5.Cu" signal "GND2")
		(14 "In6.Cu" signal "IN3")
		(16 "In7.Cu" signal "GND3")
		(18 "In8.Cu" signal "VCC")
		(20 "In9.Cu" signal "VCC1")
		(22 "In10.Cu" signal "GND4")
		(24 "In11.Cu" signal "IN4")
		(26 "In12.Cu" signal "GND5")
		(28 "In13.Cu" signal "IN5")
		(30 "In14.Cu" signal "GND6")
		(32 "In15.Cu" signal "IN6")
		(34 "In16.Cu" signal "GND7")
		(2 "B.Cu" signal "BOTTOM")
		(9 "F.Adhes" user "F.Adhesive")
		(11 "B.Adhes" user "B.Adhesive")
		(13 "F.Paste" user "Package Geometry/Pastemask Top")
		(15 "B.Paste" user "Package Geometry/Pastemask Bottom")
		(5 "F.SilkS" user "Ref Des/Silkscreen Top")
		(7 "B.SilkS" user "Ref Des/Silkscreen Bottom")
		(1 "F.Mask" user "Board Geometry/Soldermask Top")
		(3 "B.Mask" user "Board Geometry/Soldermask Bottom")
		(17 "Dwgs.User" user "User.Drawings")
		(19 "Cmts.User" user "User.Comments")
		(21 "Eco1.User" user "User.Eco1")
		(23 "Eco2.User" user "User.Eco2")
		(25 "Edge.Cuts" user "Board Geometry/Outline")
		(27 "Margin" user)
		(31 "F.CrtYd" user "Package Geometry/Place Bound Top")
		(29 "B.CrtYd" user "Package Geometry/Place Bound Bottom")
		(35 "F.Fab" user "Ref Des/Assembly Top")
		(33 "B.Fab" user "Ref Des/Assembly Bottom")
	)
	(footprint ""
		(layer "B.Cu")
		(at 125.773942 -366.723168 90)
		(property "Reference" "PC1270"
			(at 0 0 90)
			(layer "B.SilkS")
			(hide yes)
			(effects
				(font
					(size 1.27 1.27)
				)
				(justify mirror)
			)
		)
		(property "Value" ""
			(at 0 0 90)
			(layer "B.Fab")
			(effects
				(font
					(size 1.27 1.27)
				)
				(justify mirror)
			)
		)
		(duplicate_pad_numbers_are_jumpers no)
		(fp_line
			(start 1.524 -0.762)
			(end -1.524 -0.762)
			(stroke
				(width 0.1524)
				(type default)
			)
			(layer "B.SilkS")
		)
		(fp_line
			(start -1.524 -0.762)
			(end -1.524 0.762)
			(stroke
				(width 0.1524)
				(type default)
			)
			(layer "B.SilkS")
		)
		(fp_line
			(start 1.524 0.762)
			(end 1.524 -0.762)
			(stroke
				(width 0.1524)
				(type default)
			)
			(layer "B.SilkS")
		)
		(fp_line
			(start -1.524 0.762)
			(end 1.524 0.762)
			(stroke
				(width 0.1524)
				(type default)
			)
			(layer "B.SilkS")
		)
		(fp_line
			(start 1.1049 -0.724916)
			(end 1.1049 0.724916)
			(stroke
				(width 0.1)
				(type default)
			)
			(layer "B.Fab")
		)
		(fp_line
			(start -1.1049 -0.724916)
			(end 1.1049 -0.724916)
			(stroke
				(width 0.1)
				(type default)
			)
			(layer "B.Fab")
		)
		(fp_line
			(start 1.1049 0.724916)
			(end -1.1049 0.724916)
			(stroke
				(width 0.1)
				(type default)
			)
			(layer "B.Fab")
		)
		(fp_line
			(start -1.1049 0.724916)
			(end -1.1049 -0.724916)
			(stroke
				(width 0.1)
				(type default)
			)
			(layer "B.Fab")
		)
		(pad "1" smd rect
			(at 0.889 0 90)
			(size 1.016 1.27)
			(layers "B.Cu" "B.Mask" "B.Paste")
			(net "PVPP_HBM_CPU1")
		)
		(pad "2" smd rect
			(at -0.889 0 90)
			(size 1.016 1.27)
			(layers "B.Cu" "B.Mask" "B.Paste")
			(net "GND")
		)
	)
	(footprint ""
		(layer "B.Cu")
		(at 124.09678 -359.364534 -90)
		(property "Reference" "PR3336"
			(at 0 0 90)
			(layer "B.SilkS")
			(hide yes)
			(effects
				(font
					(size 1.27 1.27)
				)
				(justify mirror)
			)
		)
		(property "Value" ""
			(at 0 0 90)
			(layer "B.Fab")
			(effects
				(font
					(size 1.27 1.27)
				)
				(justify mirror)
			)
		)
		(duplicate_pad_numbers_are_jumpers no)
		(fp_line
			(start -0.7874 0.4064)
			(end 0.7874 0.4064)
			(stroke
				(width 0.1524)
				(type default)
			)
			(layer "B.SilkS")
		)
		(fp_line
			(start 0.7874 0.4064)
			(end 0.7874 -0.4064)
			(stroke
				(width 0.1524)
				(type default)
			)
			(layer "B.SilkS")
		)
		(fp_line
			(start -0.7874 -0.4064)
			(end -0.7874 0.4064)
			(stroke
				(width 0.1524)
				(type default)
			)
			(layer "B.SilkS")
		)
		(fp_line
			(start 0.7874 -0.4064)
			(end -0.7874 -0.4064)
			(stroke
				(width 0.1524)
				(type default)
			)
			(layer "B.SilkS")
		)
		(fp_line
			(start -0.67945 0.3048)
			(end -0.120396 0.3048)
			(stroke
				(width 0.1)
				(type default)
			)
			(layer "B.Fab")
		)
		(fp_line
			(start -0.120396 0.3048)
			(end -0.120396 0.2794)
			(stroke
				(width 0.1)
				(type default)
			)
			(layer "B.Fab")
		)
		(fp_line
			(start 0.12065 0.3048)
			(end 0.67945 0.3048)
			(stroke
				(width 0.1)
				(type default)
			)
			(layer "B.Fab")
		)
		(fp_line
			(start 0.67945 0.3048)
			(end 0.67945 -0.305054)
			(stroke
				(width 0.1)
				(type default)
			)
			(layer "B.Fab")
		)
		(fp_line
			(start -0.120396 0.2794)
			(end 0.12065 0.2794)
			(stroke
				(width 0.1)
				(type default)
			)
			(layer "B.Fab")
		)
		(fp_line
			(start 0.12065 0.2794)
			(end 0.12065 0.3048)
			(stroke
				(width 0.1)
				(type default)
			)
			(layer "B.Fab")
		)
		(fp_line
			(start -0.12065 -0.2794)
			(end -0.12065 -0.3048)
			(stroke
				(width 0.1)
				(type default)
			)
			(layer "B.Fab")
		)
		(fp_line
			(start 0.12065 -0.2794)
			(end -0.12065 -0.2794)
			(stroke
				(width 0.1)
				(type default)
			)
			(layer "B.Fab")
		)
		(fp_line
			(start -0.67945 -0.3048)
			(end -0.67945 0.3048)
			(stroke
				(width 0.1)
				(type default)
			)
			(layer "B.Fab")
		)
		(fp_line
			(start -0.12065 -0.3048)
			(end -0.67945 -0.3048)
			(stroke
				(width 0.1)
				(type default)
			)
			(layer "B.Fab")
		)
		(fp_line
			(start 0.12065 -0.305054)
			(end 0.12065 -0.2794)
			(stroke
				(width 0.1)
				(type default)
			)
			(layer "B.Fab")
		)
		(fp_line
			(start 0.67945 -0.305054)
			(end 0.12065 -0.305054)
			(stroke
				(width 0.1)
				(type default)
			)
			(layer "B.Fab")
		)
		(pad "1" smd circle
			(at 0.40005 0 90)
			(size 0 0)
			(layers "B.Cu" "B.Mask" "B.Paste")
			(net "PVPP_HBM_CPU1_MODE")
		)
		(pad "2" smd circle
			(at -0.40005 0 90)
			(size 0 0)
			(layers "B.Cu" "B.Mask" "B.Paste")
			(net "GND")
		)
	)
	(footprint ""
		(layer "B.Cu")
		(at 127.83566 -36.759388 90)
		(property "Reference" "R4285"
			(at 0 0 90)
			(layer "B.SilkS")
			(hide yes)
			(effects
				(font
					(size 1.27 1.27)
				)
				(justify mirror)
			)
		)
		(property "Value" ""
			(at 0 0 90)
			(layer "B.Fab")
			(effects
				(font
					(size 1.27 1.27)
				)
				(justify mirror)
			)
		)
		(duplicate_pad_numbers_are_jumpers no)
		(fp_line
			(start 0.7874 -0.4064)
			(end -0.7874 -0.4064)
			(stroke
				(width 0.1524)
				(type default)
			)
			(layer "B.SilkS")
		)
		(fp_line
			(start -0.7874 -0.4064)
			(end -0.7874 0.4064)
			(stroke
				(width 0.1524)
				(type default)
			)
			(layer "B.SilkS")
		)
		(fp_line
			(start 0.7874 0.4064)
			(end 0.7874 -0.4064)
			(stroke
				(width 0.1524)
				(type default)
			)
			(layer "B.SilkS")
		)
		(fp_line
			(start -0.7874 0.4064)
			(end 0.7874 0.4064)
			(stroke
				(width 0.1524)
				(type default)
			)
			(layer "B.SilkS")
		)
		(fp_line
			(start 0.67945 -0.305054)
			(end 0.12065 -0.305054)
			(stroke
				(width 0.1)
				(type default)
			)
			(layer "B.Fab")
		)
		(fp_line
			(start 0.12065 -0.305054)
			(end 0.12065 -0.2794)
			(stroke
				(width 0.1)
				(type default)
			)
			(layer "B.Fab")
		)
		(fp_line
			(start -0.12065 -0.3048)
			(end -0.67945 -0.3048)
			(stroke
				(width 0.1)
				(type default)
			)
			(layer "B.Fab")
		)
		(fp_line
			(start -0.67945 -0.3048)
			(end -0.67945 0.3048)
			(stroke
				(width 0.1)
				(type default)
			)
			(layer "B.Fab")
		)
		(fp_line
			(start 0.12065 -0.2794)
			(end -0.12065 -0.2794)
			(stroke
				(width 0.1)
				(type default)
			)
			(layer "B.Fab")
		)
		(fp_line
			(start -0.12065 -0.2794)
			(end -0.12065 -0.3048)
			(stroke
				(width 0.1)
				(type default)
			)
			(layer "B.Fab")
		)
		(fp_line
			(start 0.12065 0.2794)
			(end 0.12065 0.3048)
			(stroke
				(width 0.1)
				(type default)
			)
			(layer "B.Fab")
		)
		(fp_line
			(start -0.120396 0.2794)
			(end 0.12065 0.2794)
			(stroke
				(width 0.1)
				(type default)
			)
			(layer "B.Fab")
		)
		(fp_line
			(start 0.67945 0.3048)
			(end 0.67945 -0.305054)
			(stroke
				(width 0.1)
				(type default)
			)
			(layer "B.Fab")
		)
		(fp_line
			(start 0.12065 0.3048)
			(end 0.67945 0.3048)
			(stroke
				(width 0.1)
				(type default)
			)
			(layer "B.Fab")
		)
		(fp_line
			(start -0.120396 0.3048)
			(end -0.120396 0.2794)
			(stroke
				(width 0.1)
				(type default)
			)
			(layer "B.Fab")
		)
		(fp_line
			(start -0.67945 0.3048)
			(end -0.120396 0.3048)
			(stroke
				(width 0.1)
				(type default)
			)
			(layer "B.Fab")
		)
		(pad "1" smd circle
			(at 0.40005 0 270)
			(size 0 0)
			(layers "B.Cu" "B.Mask" "B.Paste")
			(net "FM_USB3_1_SWB")
		)
		(pad "2" smd circle
			(at -0.40005 0 270)
			(size 0 0)
			(layers "B.Cu" "B.Mask" "B.Paste")
			(net "GND")
		)
	)
	(footprint ""
		(layer "B.Cu")
		(at 71.385684 -190.744856 90)
		(property "Reference" "R56"
			(at 0 0 90)
			(layer "B.SilkS")
			(hide yes)
			(effects
				(font
					(size 1.27 1.27)
				)
				(justify mirror)
			)
		)
		(property "Value" ""
			(at 0 0 90)
			(layer "B.Fab")
			(effects
				(font
					(size 1.27 1.27)
				)
				(justify mirror)
			)
		)
		(duplicate_pad_numbers_are_jumpers no)
		(fp_line
			(start 0.7874 -0.4064)
			(end -0.7874 -0.4064)
			(stroke
				(width 0.1524)
				(type default)
			)
			(layer "B.SilkS")
		)
		(fp_line
			(start -0.7874 -0.4064)
			(end -0.7874 0.4064)
			(stroke
				(width 0.1524)
				(type default)
			)
			(layer "B.SilkS")
		)
		(fp_line
			(start 0.7874 0.4064)
			(end 0.7874 -0.4064)
			(stroke
				(width 0.1524)
				(type default)
			)
			(layer "B.SilkS")
		)
		(fp_line
			(start -0.7874 0.4064)
			(end 0.7874 0.4064)
			(stroke
				(width 0.1524)
				(type default)
			)
			(layer "B.SilkS")
		)
		(fp_line
			(start 0.67945 -0.305054)
			(end 0.12065 -0.305054)
			(stroke
				(width 0.1)
				(type default)
			)
			(layer "B.Fab")
		)
		(fp_line
			(start 0.12065 -0.305054)
			(end 0.12065 -0.2794)
			(stroke
				(width 0.1)
				(type default)
			)
			(layer "B.Fab")
		)
		(fp_line
			(start -0.12065 -0.3048)
			(end -0.67945 -0.3048)
			(stroke
				(width 0.1)
				(type default)
			)
			(layer "B.Fab")
		)
		(fp_line
			(start -0.67945 -0.3048)
			(end -0.67945 0.3048)
			(stroke
				(width 0.1)
				(type default)
			)
			(layer "B.Fab")
		)
		(fp_line
			(start 0.12065 -0.2794)
			(end -0.12065 -0.2794)
			(stroke
				(width 0.1)
				(type default)
			)
			(layer "B.Fab")
		)
		(fp_line
			(start -0.12065 -0.2794)
			(end -0.12065 -0.3048)
			(stroke
				(width 0.1)
				(type default)
			)
			(layer "B.Fab")
		)
		(fp_line
			(start 0.12065 0.2794)
			(end 0.12065 0.3048)
			(stroke
				(width 0.1)
				(type default)
			)
			(layer "B.Fab")
		)
		(fp_line
			(start -0.120396 0.2794)
			(end 0.12065 0.2794)
			(stroke
				(width 0.1)
				(type default)
			)
			(layer "B.Fab")
		)
		(fp_line
			(start 0.67945 0.3048)
			(end 0.67945 -0.305054)
			(stroke
				(width 0.1)
				(type default)
			)
			(layer "B.Fab")
		)
		(fp_line
			(start 0.12065 0.3048)
			(end 0.67945 0.3048)
			(stroke
				(width 0.1)
				(type default)
			)
			(layer "B.Fab")
		)
		(fp_line
			(start -0.120396 0.3048)
			(end -0.120396 0.2794)
			(stroke
				(width 0.1)
				(type default)
			)
			(layer "B.Fab")
		)
		(fp_line
			(start -0.67945 0.3048)
			(end -0.120396 0.3048)
			(stroke
				(width 0.1)
				(type default)
			)
			(layer "B.Fab")
		)
		(pad "1" smd circle
			(at 0.40005 0 270)
			(size 0 0)
			(layers "B.Cu" "B.Mask" "B.Paste")
			(net "SVID_CLK0_CPU1")
		)
		(pad "2" smd circle
			(at -0.40005 0 270)
			(size 0 0)
			(layers "B.Cu" "B.Mask" "B.Paste")
			(net "SVID_CLK0_CPU1_R")
		)
	)
	(footprint ""
		(layer "B.Cu")
		(at 330.11999 -346.808298 -90)
		(property "Reference" "PC239_P0_7"
			(at 0 0 90)
			(layer "B.SilkS")
			(hide yes)
			(effects
				(font
					(size 1.27 1.27)
				)
				(justify mirror)
			)
		)
		(property "Value" ""
			(at 0 0 90)
			(layer "B.Fab")
			(effects
				(font
					(size 1.27 1.27)
				)
				(justify mirror)
			)
		)
		(duplicate_pad_numbers_are_jumpers no)
		(fp_line
			(start -1.524 0.762)
			(end 1.524 0.762)
			(stroke
				(width 0.1524)
				(type default)
			)
			(layer "B.SilkS")
		)
		(fp_line
			(start 1.524 0.762)
			(end 1.524 -0.762)
			(stroke
				(width 0.1524)
				(type default)
			)
			(layer "B.SilkS")
		)
		(fp_line
			(start -1.524 -0.762)
			(end -1.524 0.762)
			(stroke
				(width 0.1524)
				(type default)
			)
			(layer "B.SilkS")
		)
		(fp_line
			(start 1.524 -0.762)
			(end -1.524 -0.762)
			(stroke
				(width 0.1524)
				(type default)
			)
			(layer "B.SilkS")
		)
		(fp_line
			(start -1.1049 0.724916)
			(end -1.1049 -0.724916)
			(stroke
				(width 0.1)
				(type default)
			)
			(layer "B.Fab")
		)
		(fp_line
			(start 1.1049 0.724916)
			(end -1.1049 0.724916)
			(stroke
				(width 0.1)
				(type default)
			)
			(layer "B.Fab")
		)
		(fp_line
			(start -1.1049 -0.724916)
			(end 1.1049 -0.724916)
			(stroke
				(width 0.1)
				(type default)
			)
			(layer "B.Fab")
		)
		(fp_line
			(start 1.1049 -0.724916)
			(end 1.1049 0.724916)
			(stroke
				(width 0.1)
				(type default)
			)
			(layer "B.Fab")
		)
		(pad "1" smd rect
			(at 0.889 0 270)
			(size 1.016 1.27)
			(layers "B.Cu" "B.Mask" "B.Paste")
			(net "SW_P12V_PVCCIN_CPU0_FLT")
		)
		(pad "2" smd rect
			(at -0.889 0 270)
			(size 1.016 1.27)
			(layers "B.Cu" "B.Mask" "B.Paste")
			(net "GND")
		)
	)
	(footprint ""
		(layer "B.Cu")
		(at 407.91257 -182.776368 180)
		(property "Reference" "PC205_P0_2"
			(at 0 0 0)
			(layer "B.SilkS")
			(hide yes)
			(effects
				(font
					(size 1.27 1.27)
				)
				(justify mirror)
			)
		)
		(property "Value" ""
			(at 0 0 0)
			(layer "B.Fab")
			(effects
				(font
					(size 1.27 1.27)
				)
				(justify mirror)
			)
		)
		(duplicate_pad_numbers_are_jumpers no)
		(fp_line
			(start 1.524 0.762)
			(end 1.524 -0.762)
			(stroke
				(width 0.1524)
				(type default)
			)
			(layer "B.SilkS")
		)
		(fp_line
			(start 1.524 -0.762)
			(end -1.524 -0.762)
			(stroke
				(width 0.1524)
				(type default)
			)
			(layer "B.SilkS")
		)
		(fp_line
			(start -1.524 0.762)
			(end 1.524 0.762)
			(stroke
				(width 0.1524)
				(type default)
			)
			(layer "B.SilkS")
		)
		(fp_line
			(start -1.524 -0.762)
			(end -1.524 0.762)
			(stroke
				(width 0.1524)
				(type default)
			)
			(layer "B.SilkS")
		)
		(fp_line
			(start 1.1049 0.724916)
			(end -1.1049 0.724916)
			(stroke
				(width 0.1)
				(type default)
			)
			(layer "B.Fab")
		)
		(fp_line
			(start 1.1049 -0.724916)
			(end 1.1049 0.724916)
			(stroke
				(width 0.1)
				(type default)
			)
			(layer "B.Fab")
		)
		(fp_line
			(start -1.1049 0.724916)
			(end -1.1049 -0.724916)
			(stroke
				(width 0.1)
				(type default)
			)
			(layer "B.Fab")
		)
		(fp_line
			(start -1.1049 -0.724916)
			(end 1.1049 -0.724916)
			(stroke
				(width 0.1)
				(type default)
			)
			(layer "B.Fab")
		)
		(pad "1" smd rect
			(at 0.889 0 180)
			(size 1.016 1.27)
			(layers "B.Cu" "B.Mask" "B.Paste")
			(net "PVCCINFAON_CPU0")
		)
		(pad "2" smd rect
			(at -0.889 0 180)
			(size 1.016 1.27)
			(layers "B.Cu" "B.Mask" "B.Paste")
			(net "GND")
		)
	)
	(footprint ""
		(layer "B.Cu")
		(at 365.816134 -237.709202 -90)
		(property "Reference" "C533"
			(at 0 0 90)
			(layer "B.SilkS")
			(hide yes)
			(effects
				(font
					(size 1.27 1.27)
				)
				(justify mirror)
			)
		)
		(property "Value" ""
			(at 0 0 90)
			(layer "B.Fab")
			(effects
				(font
					(size 1.27 1.27)
				)
				(justify mirror)
			)
		)
		(duplicate_pad_numbers_are_jumpers no)
		(fp_line
			(start -1.2954 0.5842)
			(end 1.2954 0.5842)
			(stroke
				(width 0.1524)
				(type default)
			)
			(layer "B.SilkS")
		)
		(fp_line
			(start 1.2954 0.5842)
			(end 1.2954 -0.5842)
			(stroke
				(width 0.1524)
				(type default)
			)
			(layer "B.SilkS")
		)
		(fp_line
			(start -1.2954 -0.5842)
			(end -1.2954 0.5842)
			(stroke
				(width 0.1524)
				(type default)
			)
			(layer "B.SilkS")
		)
		(fp_line
			(start 0 -0.5842)
			(end 0 0.5842)
			(stroke
				(width 0.1524)
				(type default)
			)
			(layer "B.SilkS")
		)
		(fp_line
			(start 1.2954 -0.5842)
			(end -1.2954 -0.5842)
			(stroke
				(width 0.1524)
				(type default)
			)
			(layer "B.SilkS")
		)
		(fp_line
			(start -0.8636 0.4572)
			(end 0.8636 0.4572)
			(stroke
				(width 0.1)
				(type default)
			)
			(layer "B.Fab")
		)
		(fp_line
			(start 0.8636 0.4572)
			(end 0.8636 0.4064)
			(stroke
				(width 0.1)
				(type default)
			)
			(layer "B.Fab")
		)
		(fp_line
			(start -1.1938 0.4064)
			(end -0.8636 0.4064)
			(stroke
				(width 0.1)
				(type default)
			)
			(layer "B.Fab")
		)
		(fp_line
			(start -0.8636 0.4064)
			(end -0.8636 0.4572)
			(stroke
				(width 0.1)
				(type default)
			)
			(layer "B.Fab")
		)
		(fp_line
			(start 0.8636 0.4064)
			(end 1.1938 0.4064)
			(stroke
				(width 0.1)
				(type default)
			)
			(layer "B.Fab")
		)
		(fp_line
			(start 1.1938 0.4064)
			(end 1.1938 -0.4064)
			(stroke
				(width 0.1)
				(type default)
			)
			(layer "B.Fab")
		)
		(fp_line
			(start -1.1938 -0.4064)
			(end -1.1938 0.4064)
			(stroke
				(width 0.1)
				(type default)
			)
			(layer "B.Fab")
		)
		(fp_line
			(start -0.8636 -0.4064)
			(end -1.1938 -0.4064)
			(stroke
				(width 0.1)
				(type default)
			)
			(layer "B.Fab")
		)
		(fp_line
			(start 0.8636 -0.4064)
			(end 0.8636 -0.4572)
			(stroke
				(width 0.1)
				(type default)
			)
			(layer "B.Fab")
		)
		(fp_line
			(start 1.1938 -0.4064)
			(end 0.8636 -0.4064)
			(stroke
				(width 0.1)
				(type default)
			)
			(layer "B.Fab")
		)
		(fp_line
			(start -0.8636 -0.4572)
			(end -0.8636 -0.4064)
			(stroke
				(width 0.1)
				(type default)
			)
			(layer "B.Fab")
		)
		(fp_line
			(start 0.8636 -0.4572)
			(end -0.8636 -0.4572)
			(stroke
				(width 0.1)
				(type default)
			)
			(layer "B.Fab")
		)
		(pad "1" smd rect
			(at 0.7366 0 180)
			(size 0.7112 0.8128)
			(layers "B.Cu" "B.Mask" "B.Paste")
			(net "PVCCINFAON_CPU0")
		)
		(pad "2" smd rect
			(at -0.7366 0 180)
			(size 0.7112 0.8128)
			(layers "B.Cu" "B.Mask" "B.Paste")
			(net "GND")
		)
	)
)
